(kicad_pcb
	(version 20260206)
	(generator "pcbnew")
	(generator_version "10.0")
	(general
		(thickness 1.6)
		(legacy_teardrops no)
	)
	(paper "A4")
	(title_block
		(title "12092022_DA0F0TMDCD0_F0T_Management_Board_D_brd_V3_OCP.brd")
		(comment 1 "Grand Teton / footprints 810-816 of 1440")
	)
	(layers
		(0 "F.Cu" signal "TOP")
		(4 "In1.Cu" signal "GND")
		(6 "In2.Cu" signal "IN1")
		(8 "In3.Cu" signal "GND1")
		(10 "In4.Cu" signal "IN2")
		(12 "In5.Cu" signal "VCC")
		(14 "In6.Cu" signal "VCC1")
		(16 "In7.Cu" signal "IN3")
		(18 "In8.Cu" signal "GND2")
		(20 "In9.Cu" signal "IN4")
		(22 "In10.Cu" signal "GND3")
		(2 "B.Cu" signal "BOTTOM")
		(9 "F.Adhes" user "F.Adhesive")
		(11 "B.Adhes" user "B.Adhesive")
		(13 "F.Paste" user "Package Geometry/Pastemask Top")
		(15 "B.Paste" user "Package Geometry/Pastemask Bottom")
		(5 "F.SilkS" user "Ref Des/Silkscreen Top")
		(7 "B.SilkS" user "Ref Des/Silkscreen Bottom")
		(1 "F.Mask" user "Board Geometry/Soldermask Top")
		(3 "B.Mask" user "Board Geometry/Soldermask Bottom")
		(17 "Dwgs.User" user "User.Drawings")
		(19 "Cmts.User" user "User.Comments")
		(21 "Eco1.User" user "User.Eco1")
		(23 "Eco2.User" user "User.Eco2")
		(25 "Edge.Cuts" user "Board Geometry/Outline")
		(27 "Margin" user)
		(31 "F.CrtYd" user "Package Geometry/Place Bound Top")
		(29 "B.CrtYd" user "Package Geometry/Place Bound Bottom")
		(35 "F.Fab" user "Ref Des/Assembly Top")
		(33 "B.Fab" user "Ref Des/Assembly Bottom")
	)
	(footprint ""
		(layer "B.Cu")
		(at 50.240692 -55.170832)
		(property "Reference" "C115"
			(at 0 0 0)
			(layer "B.SilkS")
			(hide yes)
			(effects
				(font
					(size 1.27 1.27)
				)
				(justify mirror)
			)
		)
		(property "Value" ""
			(at 0 0 0)
			(layer "B.Fab")
			(effects
				(font
					(size 1.27 1.27)
				)
				(justify mirror)
			)
		)
		(duplicate_pad_numbers_are_jumpers no)
		(fp_line
			(start -0.7874 -0.4064)
			(end -0.7874 0.4064)
			(stroke
				(width 0.1524)
				(type default)
			)
			(layer "B.SilkS")
		)
		(fp_line
			(start -0.7874 0.4064)
			(end 0.7874 0.4064)
			(stroke
				(width 0.1524)
				(type default)
			)
			(layer "B.SilkS")
		)
		(fp_line
			(start 0.7874 -0.4064)
			(end -0.7874 -0.4064)
			(stroke
				(width 0.1524)
				(type default)
			)
			(layer "B.SilkS")
		)
		(fp_line
			(start 0.7874 0.4064)
			(end 0.7874 -0.4064)
			(stroke
				(width 0.1524)
				(type default)
			)
			(layer "B.SilkS")
		)
		(fp_line
			(start -0.67945 -0.3048)
			(end -0.67945 0.3048)
			(stroke
				(width 0.1)
				(type default)
			)
			(layer "B.Fab")
		)
		(fp_line
			(start -0.67945 0.3048)
			(end -0.120396 0.3048)
			(stroke
				(width 0.1)
				(type default)
			)
			(layer "B.Fab")
		)
		(fp_line
			(start -0.12065 -0.3048)
			(end -0.67945 -0.3048)
			(stroke
				(width 0.1)
				(type default)
			)
			(layer "B.Fab")
		)
		(fp_line
			(start -0.12065 -0.2794)
			(end -0.12065 -0.3048)
			(stroke
				(width 0.1)
				(type default)
			)
			(layer "B.Fab")
		)
		(fp_line
			(start -0.120396 0.2794)
			(end 0.12065 0.2794)
			(stroke
				(width 0.1)
				(type default)
			)
			(layer "B.Fab")
		)
		(fp_line
			(start -0.120396 0.3048)
			(end -0.120396 0.2794)
			(stroke
				(width 0.1)
				(type default)
			)
			(layer "B.Fab")
		)
		(fp_line
			(start 0.12065 -0.305054)
			(end 0.12065 -0.2794)
			(stroke
				(width 0.1)
				(type default)
			)
			(layer "B.Fab")
		)
		(fp_line
			(start 0.12065 -0.2794)
			(end -0.12065 -0.2794)
			(stroke
				(width 0.1)
				(type default)
			)
			(layer "B.Fab")
		)
		(fp_line
			(start 0.12065 0.2794)
			(end 0.12065 0.3048)
			(stroke
				(width 0.1)
				(type default)
			)
			(layer "B.Fab")
		)
		(fp_line
			(start 0.12065 0.3048)
			(end 0.67945 0.3048)
			(stroke
				(width 0.1)
				(type default)
			)
			(layer "B.Fab")
		)
		(fp_line
			(start 0.67945 -0.305054)
			(end 0.12065 -0.305054)
			(stroke
				(width 0.1)
				(type default)
			)
			(layer "B.Fab")
		)
		(fp_line
			(start 0.67945 0.3048)
			(end 0.67945 -0.305054)
			(stroke
				(width 0.1)
				(type default)
			)
			(layer "B.Fab")
		)
		(pad "1" smd circle
			(at 0.40005 0 180)
			(size 0 0)
			(layers "B.Cu" "B.Mask" "B.Paste")
			(net "P3V3_AUX")
		)
		(pad "2" smd circle
			(at -0.40005 0 180)
			(size 0 0)
			(layers "B.Cu" "B.Mask" "B.Paste")
			(net "GND")
		)
	)
	(footprint ""
		(layer "B.Cu")
		(at 47.846742 -73.957688 180)
		(property "Reference" "R776"
			(at 0 0 0)
			(layer "B.SilkS")
			(hide yes)
			(effects
				(font
					(size 1.27 1.27)
				)
				(justify mirror)
			)
		)
		(property "Value" ""
			(at 0 0 0)
			(layer "B.Fab")
			(effects
				(font
					(size 1.27 1.27)
				)
				(justify mirror)
			)
		)
		(duplicate_pad_numbers_are_jumpers no)
		(fp_line
			(start 0.7874 0.4064)
			(end 0.7874 -0.4064)
			(stroke
				(width 0.1524)
				(type default)
			)
			(layer "B.SilkS")
		)
		(fp_line
			(start 0.7874 -0.4064)
			(end -0.7874 -0.4064)
			(stroke
				(width 0.1524)
				(type default)
			)
			(layer "B.SilkS")
		)
		(fp_line
			(start -0.7874 0.4064)
			(end 0.7874 0.4064)
			(stroke
				(width 0.1524)
				(type default)
			)
			(layer "B.SilkS")
		)
		(fp_line
			(start -0.7874 -0.4064)
			(end -0.7874 0.4064)
			(stroke
				(width 0.1524)
				(type default)
			)
			(layer "B.SilkS")
		)
		(fp_line
			(start 0.67945 0.3048)
			(end 0.67945 -0.305054)
			(stroke
				(width 0.1)
				(type default)
			)
			(layer "B.Fab")
		)
		(fp_line
			(start 0.67945 -0.305054)
			(end 0.12065 -0.305054)
			(stroke
				(width 0.1)
				(type default)
			)
			(layer "B.Fab")
		)
		(fp_line
			(start 0.12065 0.3048)
			(end 0.67945 0.3048)
			(stroke
				(width 0.1)
				(type default)
			)
			(layer "B.Fab")
		)
		(fp_line
			(start 0.12065 0.2794)
			(end 0.12065 0.3048)
			(stroke
				(width 0.1)
				(type default)
			)
			(layer "B.Fab")
		)
		(fp_line
			(start 0.12065 -0.2794)
			(end -0.12065 -0.2794)
			(stroke
				(width 0.1)
				(type default)
			)
			(layer "B.Fab")
		)
		(fp_line
			(start 0.12065 -0.305054)
			(end 0.12065 -0.2794)
			(stroke
				(width 0.1)
				(type default)
			)
			(layer "B.Fab")
		)
		(fp_line
			(start -0.120396 0.3048)
			(end -0.120396 0.2794)
			(stroke
				(width 0.1)
				(type default)
			)
			(layer "B.Fab")
		)
		(fp_line
			(start -0.120396 0.2794)
			(end 0.12065 0.2794)
			(stroke
				(width 0.1)
				(type default)
			)
			(layer "B.Fab")
		)
		(fp_line
			(start -0.12065 -0.2794)
			(end -0.12065 -0.3048)
			(stroke
				(width 0.1)
				(type default)
			)
			(layer "B.Fab")
		)
		(fp_line
			(start -0.12065 -0.3048)
			(end -0.67945 -0.3048)
			(stroke
				(width 0.1)
				(type default)
			)
			(layer "B.Fab")
		)
		(fp_line
			(start -0.67945 0.3048)
			(end -0.120396 0.3048)
			(stroke
				(width 0.1)
				(type default)
			)
			(layer "B.Fab")
		)
		(fp_line
			(start -0.67945 -0.3048)
			(end -0.67945 0.3048)
			(stroke
				(width 0.1)
				(type default)
			)
			(layer "B.Fab")
		)
		(pad "1" smd circle
			(at 0.40005 0)
			(size 0 0)
			(layers "B.Cu" "B.Mask" "B.Paste")
			(net "BATTERY_DETECT_R")
		)
		(pad "2" smd circle
			(at -0.40005 0)
			(size 0 0)
			(layers "B.Cu" "B.Mask" "B.Paste")
			(net "GND")
		)
	)
	(footprint ""
		(layer "B.Cu")
		(at 53.337968 -43.761406 180)
		(property "Reference" "C110"
			(at 0 0 0)
			(layer "B.SilkS")
			(hide yes)
			(effects
				(font
					(size 1.27 1.27)
				)
				(justify mirror)
			)
		)
		(property "Value" ""
			(at 0 0 0)
			(layer "B.Fab")
			(effects
				(font
					(size 1.27 1.27)
				)
				(justify mirror)
			)
		)
		(duplicate_pad_numbers_are_jumpers no)
		(fp_line
			(start 0.7874 0.4064)
			(end 0.7874 -0.4064)
			(stroke
				(width 0.1524)
				(type default)
			)
			(layer "B.SilkS")
		)
		(fp_line
			(start 0.7874 -0.4064)
			(end -0.7874 -0.4064)
			(stroke
				(width 0.1524)
				(type default)
			)
			(layer "B.SilkS")
		)
		(fp_line
			(start -0.7874 0.4064)
			(end 0.7874 0.4064)
			(stroke
				(width 0.1524)
				(type default)
			)
			(layer "B.SilkS")
		)
		(fp_line
			(start -0.7874 -0.4064)
			(end -0.7874 0.4064)
			(stroke
				(width 0.1524)
				(type default)
			)
			(layer "B.SilkS")
		)
		(fp_line
			(start 0.67945 0.3048)
			(end 0.67945 -0.305054)
			(stroke
				(width 0.1)
				(type default)
			)
			(layer "B.Fab")
		)
		(fp_line
			(start 0.67945 -0.305054)
			(end 0.12065 -0.305054)
			(stroke
				(width 0.1)
				(type default)
			)
			(layer "B.Fab")
		)
		(fp_line
			(start 0.12065 0.3048)
			(end 0.67945 0.3048)
			(stroke
				(width 0.1)
				(type default)
			)
			(layer "B.Fab")
		)
		(fp_line
			(start 0.12065 0.2794)
			(end 0.12065 0.3048)
			(stroke
				(width 0.1)
				(type default)
			)
			(layer "B.Fab")
		)
		(fp_line
			(start 0.12065 -0.2794)
			(end -0.12065 -0.2794)
			(stroke
				(width 0.1)
				(type default)
			)
			(layer "B.Fab")
		)
		(fp_line
			(start 0.12065 -0.305054)
			(end 0.12065 -0.2794)
			(stroke
				(width 0.1)
				(type default)
			)
			(layer "B.Fab")
		)
		(fp_line
			(start -0.120396 0.3048)
			(end -0.120396 0.2794)
			(stroke
				(width 0.1)
				(type default)
			)
			(layer "B.Fab")
		)
		(fp_line
			(start -0.120396 0.2794)
			(end 0.12065 0.2794)
			(stroke
				(width 0.1)
				(type default)
			)
			(layer "B.Fab")
		)
		(fp_line
			(start -0.12065 -0.2794)
			(end -0.12065 -0.3048)
			(stroke
				(width 0.1)
				(type default)
			)
			(layer "B.Fab")
		)
		(fp_line
			(start -0.12065 -0.3048)
			(end -0.67945 -0.3048)
			(stroke
				(width 0.1)
				(type default)
			)
			(layer "B.Fab")
		)
		(fp_line
			(start -0.67945 0.3048)
			(end -0.120396 0.3048)
			(stroke
				(width 0.1)
				(type default)
			)
			(layer "B.Fab")
		)
		(fp_line
			(start -0.67945 -0.3048)
			(end -0.67945 0.3048)
			(stroke
				(width 0.1)
				(type default)
			)
			(layer "B.Fab")
		)
		(pad "1" smd circle
			(at 0.40005 0)
			(size 0 0)
			(layers "B.Cu" "B.Mask" "B.Paste")
			(net "P3V3_AUX")
		)
		(pad "2" smd circle
			(at -0.40005 0)
			(size 0 0)
			(layers "B.Cu" "B.Mask" "B.Paste")
			(net "GND")
		)
	)
	(footprint ""
		(layer "B.Cu")
		(at 26.259536 -89.98712 180)
		(property "Reference" "C218"
			(at 0 0 0)
			(layer "B.SilkS")
			(hide yes)
			(effects
				(font
					(size 1.27 1.27)
				)
				(justify mirror)
			)
		)
		(property "Value" ""
			(at 0 0 0)
			(layer "B.Fab")
			(effects
				(font
					(size 1.27 1.27)
				)
				(justify mirror)
			)
		)
		(duplicate_pad_numbers_are_jumpers no)
		(fp_line
			(start 0.69215 0.2921)
			(end 0.69215 -0.2921)
			(stroke
				(width 0.1524)
				(type default)
			)
			(layer "B.SilkS")
		)
		(fp_line
			(start 0.69215 -0.2921)
			(end -0.69215 -0.2921)
			(stroke
				(width 0.1524)
				(type default)
			)
			(layer "B.SilkS")
		)
		(fp_line
			(start -0.69215 0.2921)
			(end 0.69215 0.2921)
			(stroke
				(width 0.1524)
				(type default)
			)
			(layer "B.SilkS")
		)
		(fp_line
			(start -0.69215 -0.2921)
			(end -0.69215 0.2921)
			(stroke
				(width 0.1524)
				(type default)
			)
			(layer "B.SilkS")
		)
		(fp_line
			(start 0.51435 0.2794)
			(end 0.51435 -0.2794)
			(stroke
				(width 0.1)
				(type default)
			)
			(layer "B.Fab")
		)
		(fp_line
			(start 0.51435 -0.2794)
			(end -0.51435 -0.2794)
			(stroke
				(width 0.1)
				(type default)
			)
			(layer "B.Fab")
		)
		(fp_line
			(start -0.51435 0.2794)
			(end 0.51435 0.2794)
			(stroke
				(width 0.1)
				(type default)
			)
			(layer "B.Fab")
		)
		(fp_line
			(start -0.51435 -0.2794)
			(end -0.51435 0.2794)
			(stroke
				(width 0.1)
				(type default)
			)
			(layer "B.Fab")
		)
		(pad "1" smd circle
			(at 0.40005 0)
			(size 0 0)
			(layers "B.Cu" "B.Mask" "B.Paste")
			(net "VCCIO5")
		)
		(pad "2" smd circle
			(at -0.40005 0)
			(size 0 0)
			(layers "B.Cu" "B.Mask" "B.Paste")
			(net "GND")
		)
		(zone
			(layer "B.Cu")
			(hatch none 0.5)
			(connect_pads
				(clearance 0)
			)
			(min_thickness 0.25)
			(keepout
				(tracks not_allowed)
				(vias allowed)
				(pads allowed)
				(copperpour not_allowed)
				(footprints allowed)
			)
			(placement
				(enabled no)
				(sheetname "")
			)
			(fill
				(thermal_gap 0.5)
				(thermal_bridge_width 0.5)
				(island_removal_mode 0)
			)
			(polygon
				(pts
					(xy 26.069036 -90.07475) (xy 26.160476 -90.132916) (xy 26.359866 -90.132916) (xy 26.450036 -90.07475)
					(xy 26.450036 -89.89949) (xy 26.359866 -89.84107) (xy 26.160476 -89.84107) (xy 26.069036 -89.899236)
				)
			)
		)
	)
	(footprint ""
		(layer "B.Cu")
		(at 71.599806 -72.047608 -90)
		(property "Reference" "R685"
			(at 0 0 90)
			(layer "B.SilkS")
			(hide yes)
			(effects
				(font
					(size 1.27 1.27)
				)
				(justify mirror)
			)
		)
		(property "Value" ""
			(at 0 0 90)
			(layer "B.Fab")
			(effects
				(font
					(size 1.27 1.27)
				)
				(justify mirror)
			)
		)
		(duplicate_pad_numbers_are_jumpers no)
		(fp_line
			(start -0.7874 0.4064)
			(end 0.7874 0.4064)
			(stroke
				(width 0.1524)
				(type default)
			)
			(layer "B.SilkS")
		)
		(fp_line
			(start 0.7874 0.4064)
			(end 0.7874 -0.4064)
			(stroke
				(width 0.1524)
				(type default)
			)
			(layer "B.SilkS")
		)
		(fp_line
			(start -0.7874 -0.4064)
			(end -0.7874 0.4064)
			(stroke
				(width 0.1524)
				(type default)
			)
			(layer "B.SilkS")
		)
		(fp_line
			(start 0.7874 -0.4064)
			(end -0.7874 -0.4064)
			(stroke
				(width 0.1524)
				(type default)
			)
			(layer "B.SilkS")
		)
		(fp_line
			(start -0.67945 0.3048)
			(end -0.120396 0.3048)
			(stroke
				(width 0.1)
				(type default)
			)
			(layer "B.Fab")
		)
		(fp_line
			(start -0.120396 0.3048)
			(end -0.120396 0.2794)
			(stroke
				(width 0.1)
				(type default)
			)
			(layer "B.Fab")
		)
		(fp_line
			(start 0.12065 0.3048)
			(end 0.67945 0.3048)
			(stroke
				(width 0.1)
				(type default)
			)
			(layer "B.Fab")
		)
		(fp_line
			(start 0.67945 0.3048)
			(end 0.67945 -0.305054)
			(stroke
				(width 0.1)
				(type default)
			)
			(layer "B.Fab")
		)
		(fp_line
			(start -0.120396 0.2794)
			(end 0.12065 0.2794)
			(stroke
				(width 0.1)
				(type default)
			)
			(layer "B.Fab")
		)
		(fp_line
			(start 0.12065 0.2794)
			(end 0.12065 0.3048)
			(stroke
				(width 0.1)
				(type default)
			)
			(layer "B.Fab")
		)
		(fp_line
			(start -0.12065 -0.2794)
			(end -0.12065 -0.3048)
			(stroke
				(width 0.1)
				(type default)
			)
			(layer "B.Fab")
		)
		(fp_line
			(start 0.12065 -0.2794)
			(end -0.12065 -0.2794)
			(stroke
				(width 0.1)
				(type default)
			)
			(layer "B.Fab")
		)
		(fp_line
			(start -0.67945 -0.3048)
			(end -0.67945 0.3048)
			(stroke
				(width 0.1)
				(type default)
			)
			(layer "B.Fab")
		)
		(fp_line
			(start -0.12065 -0.3048)
			(end -0.67945 -0.3048)
			(stroke
				(width 0.1)
				(type default)
			)
			(layer "B.Fab")
		)
		(fp_line
			(start 0.12065 -0.305054)
			(end 0.12065 -0.2794)
			(stroke
				(width 0.1)
				(type default)
			)
			(layer "B.Fab")
		)
		(fp_line
			(start 0.67945 -0.305054)
			(end 0.12065 -0.305054)
			(stroke
				(width 0.1)
				(type default)
			)
			(layer "B.Fab")
		)
		(pad "1" smd circle
			(at 0.40005 0 90)
			(size 0 0)
			(layers "B.Cu" "B.Mask" "B.Paste")
			(net "BMC_EMMC_CD_N")
		)
		(pad "2" smd circle
			(at -0.40005 0 90)
			(size 0 0)
			(layers "B.Cu" "B.Mask" "B.Paste")
			(net "GND")
		)
	)
	(footprint ""
		(layer "B.Cu")
		(at 19.6342 -75.3618 180)
		(property "Reference" "C318"
			(at 0 0 0)
			(layer "B.SilkS")
			(hide yes)
			(effects
				(font
					(size 1.27 1.27)
				)
				(justify mirror)
			)
		)
		(property "Value" ""
			(at 0 0 0)
			(layer "B.Fab")
			(effects
				(font
					(size 1.27 1.27)
				)
				(justify mirror)
			)
		)
		(duplicate_pad_numbers_are_jumpers no)
		(fp_line
			(start 0.7874 0.4064)
			(end 0.7874 -0.4064)
			(stroke
				(width 0.1524)
				(type default)
			)
			(layer "B.SilkS")
		)
		(fp_line
			(start 0.7874 -0.4064)
			(end -0.7874 -0.4064)
			(stroke
				(width 0.1524)
				(type default)
			)
			(layer "B.SilkS")
		)
		(fp_line
			(start -0.7874 0.4064)
			(end 0.7874 0.4064)
			(stroke
				(width 0.1524)
				(type default)
			)
			(layer "B.SilkS")
		)
		(fp_line
			(start -0.7874 -0.4064)
			(end -0.7874 0.4064)
			(stroke
				(width 0.1524)
				(type default)
			)
			(layer "B.SilkS")
		)
		(fp_line
			(start 0.67945 0.3048)
			(end 0.67945 -0.305054)
			(stroke
				(width 0.1)
				(type default)
			)
			(layer "B.Fab")
		)
		(fp_line
			(start 0.67945 -0.305054)
			(end 0.12065 -0.305054)
			(stroke
				(width 0.1)
				(type default)
			)
			(layer "B.Fab")
		)
		(fp_line
			(start 0.12065 0.3048)
			(end 0.67945 0.3048)
			(stroke
				(width 0.1)
				(type default)
			)
			(layer "B.Fab")
		)
		(fp_line
			(start 0.12065 0.2794)
			(end 0.12065 0.3048)
			(stroke
				(width 0.1)
				(type default)
			)
			(layer "B.Fab")
		)
		(fp_line
			(start 0.12065 -0.2794)
			(end -0.12065 -0.2794)
			(stroke
				(width 0.1)
				(type default)
			)
			(layer "B.Fab")
		)
		(fp_line
			(start 0.12065 -0.305054)
			(end 0.12065 -0.2794)
			(stroke
				(width 0.1)
				(type default)
			)
			(layer "B.Fab")
		)
		(fp_line
			(start -0.120396 0.3048)
			(end -0.120396 0.2794)
			(stroke
				(width 0.1)
				(type default)
			)
			(layer "B.Fab")
		)
		(fp_line
			(start -0.120396 0.2794)
			(end 0.12065 0.2794)
			(stroke
				(width 0.1)
				(type default)
			)
			(layer "B.Fab")
		)
		(fp_line
			(start -0.12065 -0.2794)
			(end -0.12065 -0.3048)
			(stroke
				(width 0.1)
				(type default)
			)
			(layer "B.Fab")
		)
		(fp_line
			(start -0.12065 -0.3048)
			(end -0.67945 -0.3048)
			(stroke
				(width 0.1)
				(type default)
			)
			(layer "B.Fab")
		)
		(fp_line
			(start -0.67945 0.3048)
			(end -0.120396 0.3048)
			(stroke
				(width 0.1)
				(type default)
			)
			(layer "B.Fab")
		)
		(fp_line
			(start -0.67945 -0.3048)
			(end -0.67945 0.3048)
			(stroke
				(width 0.1)
				(type default)
			)
			(layer "B.Fab")
		)
		(pad "1" smd circle
			(at 0.40005 0)
			(size 0 0)
			(layers "B.Cu" "B.Mask" "B.Paste")
			(net "P3V3_AUX")
		)
		(pad "2" smd circle
			(at -0.40005 0)
			(size 0 0)
			(layers "B.Cu" "B.Mask" "B.Paste")
			(net "GND")
		)
	)
	(footprint ""
		(layer "B.Cu")
		(at -7.874 -109.728 180)
		(property "Reference" "DB1"
			(at 1.7526 -5.76707 0)
			(unlocked yes)
			(layer "B.SilkS")
			(effects
				(font
					(size 0.7874 0.5842)
					(thickness 0.1524)
				)
				(justify left mirror)
			)
		)
		(property "Value" ""
			(at 0 0 0)
			(layer "B.Fab")
			(effects
				(font
					(size 1.27 1.27)
				)
				(justify mirror)
			)
		)
		(duplicate_pad_numbers_are_jumpers no)
		(fp_line
			(start 3.330702 -4.771136)
			(end -3.330702 -4.771136)
			(stroke
				(width 0.1524)
				(type default)
			)
			(layer "B.SilkS")
		)
		(fp_line
			(start 0 4.011168)
			(end 3.330702 -4.771136)
			(stroke
				(width 0.1524)
				(type default)
			)
			(layer "B.SilkS")
		)
		(fp_line
			(start -3.330702 -4.771136)
			(end 0 4.011168)
			(stroke
				(width 0.1524)
				(type default)
			)
			(layer "B.SilkS")
		)
		(fp_line
			(start 3.330702 -4.771136)
			(end -3.330702 -4.771136)
			(stroke
				(width 0.1)
				(type default)
			)
			(layer "B.Fab")
		)
		(fp_line
			(start 0 4.011168)
			(end 3.330702 -4.771136)
			(stroke
				(width 0.1)
				(type default)
			)
			(layer "B.Fab")
		)
		(fp_line
			(start -3.330702 -4.771136)
			(end 0 4.011168)
			(stroke
				(width 0.1)
				(type default)
			)
			(layer "B.Fab")
		)
		(pad "1" thru_hole circle
			(at 0 0)
			(size 2.159 2.159)
			(drill 1.7018)
			(layers "*.Cu" "*.Mask")
			(remove_unused_layers no)
			(net "T_GND")
			(clearance 0.0254)
			(thermal_gap 0.0254)
		)
		(pad "2" thru_hole circle
			(at 1.27 -3.348736)
			(size 2.159 2.159)
			(drill 1.7018)
			(layers "*.Cu" "*.Mask")
			(remove_unused_layers no)
			(net "TDR_SE_50_OHM_TOP")
			(clearance 0.0254)
			(thermal_gap 0.0254)
		)
		(pad "3" thru_hole circle
			(at -1.27 -3.348736)
			(size 2.159 2.159)
			(drill 1.7018)
			(layers "*.Cu" "*.Mask")
			(remove_unused_layers no)
			(net "TDR_SE_50_OHM_TOP")
			(clearance 0.0254)
			(thermal_gap 0.0254)
		)
	)
)
